# BASEBOARD_FAB2 (Tioga Pass) — schematic netlist excerpt (pin names and nets, part order shuffled) for the footprints in the layout excerpt that follows; sources: Cadence DE-HDL packaged netlist, KiCad conversion of Wiwynn_Tioga_Pass_MB.brd

C9A5  CAP_A  0.1UF 16V 10% X7R  pkg 0402V  page 111 : A = XDP_RST_CO_N ; B = GND
R1U9  RES  20.0 1% CHIP  pkg 0402  page 159 : A = SMB_SMLINK0_STBY_LVC3_SCL_R ; B = SMB_SMLINK0_STBY_LVC3_SCL
C1R27  CAP_A  0.1UF 16V 10% X7R  pkg 0402V  page 170 : A = P3V3_STBY ; B = GND

(kicad_pcb
	(version 20260206)
	(generator "pcbnew")
	(generator_version "10.0")
	(general
		(thickness 1.6)
		(legacy_teardrops no)
	)
	(paper "A4")
	(title_block
		(title "Wiwynn_Tioga_Pass_MB.brd")
		(comment 1 "Tioga Pass / footprints 3941-3943 of 4770")
	)
	(layers
		(0 "F.Cu" signal "TOP")
		(4 "In1.Cu" signal "L2GND")
		(6 "In2.Cu" signal "L3")
		(8 "In3.Cu" signal "L4GND")
		(10 "In4.Cu" signal "L5")
		(12 "In5.Cu" signal "L6GND")
		(14 "In6.Cu" signal "L7VCC")
		(16 "In7.Cu" signal "L8VCC")
		(18 "In8.Cu" signal "L9GND")
		(20 "In9.Cu" signal "L10")
		(22 "In10.Cu" signal "L11GND")
		(24 "In11.Cu" signal "L12")
		(26 "In12.Cu" signal "L13GND")
		(2 "B.Cu" signal "BOTTOM")
		(9 "F.Adhes" user "F.Adhesive")
		(11 "B.Adhes" user "B.Adhesive")
		(13 "F.Paste" user "Package Geometry/Pastemask Top")
		(15 "B.Paste" user "Package Geometry/Pastemask Bottom")
		(5 "F.SilkS" user "Ref Des/Silkscreen Top")
		(7 "B.SilkS" user "Ref Des/Silkscreen Bottom")
		(1 "F.Mask" user "Board Geometry/Soldermask Top")
		(3 "B.Mask" user "Board Geometry/Soldermask Bottom")
		(17 "Dwgs.User" user "User.Drawings")
		(19 "Cmts.User" user "User.Comments")
		(21 "Eco1.User" user "User.Eco1")
		(23 "Eco2.User" user "User.Eco2")
		(25 "Edge.Cuts" user "Board Geometry/Outline")
		(27 "Margin" user)
		(31 "F.CrtYd" user "Package Geometry/Place Bound Top")
		(29 "B.CrtYd" user "Package Geometry/Place Bound Bottom")
		(35 "F.Fab" user "Ref Des/Assembly Top")
		(33 "B.Fab" user "Ref Des/Assembly Bottom")
	)
	(footprint ""
		(layer "B.Cu")
		(at 454.5838 -146.7612 -90)
		(property "Reference" "C9A5"
			(at 0 0 90)
			(layer "B.SilkS")
			(hide yes)
			(effects
				(font
					(size 1.27 1.27)
				)
				(justify mirror)
			)
		)
		(property "Value" ""
			(at 0 0 90)
			(layer "B.Fab")
			(effects
				(font
					(size 1.27 1.27)
				)
				(justify mirror)
			)
		)
		(duplicate_pad_numbers_are_jumpers no)
		(fp_poly
			(pts
				(xy -0.3048 -0.1016) (xy -0.3048 0.9906) (xy 0.3048 0.9906) (xy 0.3048 -0.1016)
			)
			(stroke
				(width 0)
				(type default)
			)
			(fill no)
			(layer "B.CrtYd")
		)
		(fp_line
			(start -0.3048 0.9906)
			(end -0.3048 -0.1016)
			(stroke
				(width 0.1)
				(type default)
			)
			(layer "B.Fab")
		)
		(fp_line
			(start 0.3048 0.9906)
			(end -0.3048 0.9906)
			(stroke
				(width 0.1)
				(type default)
			)
			(layer "B.Fab")
		)
		(fp_line
			(start -0.3048 -0.1016)
			(end 0.3048 -0.1016)
			(stroke
				(width 0.1)
				(type default)
			)
			(layer "B.Fab")
		)
		(fp_line
			(start 0.3048 -0.1016)
			(end 0.3048 0.9906)
			(stroke
				(width 0.1)
				(type default)
			)
			(layer "B.Fab")
		)
		(pad "1" smd rect
			(at 0 0 90)
			(size 0.508 0.508)
			(layers "B.Cu" "B.Mask" "B.Paste")
			(net "XDP_RST_CO_N")
		)
		(pad "2" smd rect
			(at 0 0.889 90)
			(size 0.508 0.508)
			(layers "B.Cu" "B.Mask" "B.Paste")
			(net "GND")
		)
		(zone
			(layer "B.Cu")
			(hatch none 0.5)
			(connect_pads
				(clearance 0)
			)
			(min_thickness 0.25)
			(keepout
				(tracks not_allowed)
				(vias allowed)
				(pads allowed)
				(copperpour not_allowed)
				(footprints allowed)
			)
			(placement
				(enabled no)
				(sheetname "")
			)
			(fill
				(thermal_gap 0.5)
				(thermal_bridge_width 0.5)
				(island_removal_mode 0)
			)
			(polygon
				(pts
					(xy 453.9488 -146.5072) (xy 453.9488 -147.0152) (xy 454.3298 -147.0152) (xy 454.3298 -146.5072)
				)
			)
		)
		(zone
			(layer "B.Cu")
			(hatch none 0.5)
			(connect_pads
				(clearance 0)
			)
			(min_thickness 0.25)
			(keepout
				(tracks allowed)
				(vias not_allowed)
				(pads allowed)
				(copperpour not_allowed)
				(footprints allowed)
			)
			(placement
				(enabled no)
				(sheetname "")
			)
			(fill
				(thermal_gap 0.5)
				(thermal_bridge_width 0.5)
				(island_removal_mode 0)
			)
			(polygon
				(pts
					(xy 454.3298 -146.5072) (xy 454.3298 -147.0152) (xy 453.9488 -147.0152) (xy 453.9488 -146.5072)
				)
			)
		)
	)
	(footprint ""
		(layer "B.Cu")
		(at 427.4185 -20.32 90)
		(property "Reference" "R1U9"
			(at 0 0 90)
			(layer "B.SilkS")
			(hide yes)
			(effects
				(font
					(size 1.27 1.27)
				)
				(justify mirror)
			)
		)
		(property "Value" ""
			(at 0 0 90)
			(layer "B.Fab")
			(effects
				(font
					(size 1.27 1.27)
				)
				(justify mirror)
			)
		)
		(duplicate_pad_numbers_are_jumpers no)
		(fp_poly
			(pts
				(xy 0.2794 -0.1016) (xy -0.2794 -0.1016) (xy -0.2794 0.9906) (xy 0.2794 0.9906)
			)
			(stroke
				(width 0)
				(type default)
			)
			(fill no)
			(layer "B.CrtYd")
		)
		(fp_line
			(start 0.2794 -0.1016)
			(end 0.2794 0.9906)
			(stroke
				(width 0.1)
				(type default)
			)
			(layer "B.Fab")
		)
		(fp_line
			(start -0.2794 -0.1016)
			(end 0.2794 -0.1016)
			(stroke
				(width 0.1)
				(type default)
			)
			(layer "B.Fab")
		)
		(fp_line
			(start 0.2794 0.9906)
			(end -0.2794 0.9906)
			(stroke
				(width 0.1)
				(type default)
			)
			(layer "B.Fab")
		)
		(fp_line
			(start -0.2794 0.9906)
			(end -0.2794 -0.1016)
			(stroke
				(width 0.1)
				(type default)
			)
			(layer "B.Fab")
		)
		(pad "1" smd rect
			(at 0 0 270)
			(size 0.508 0.508)
			(layers "B.Cu" "B.Mask" "B.Paste")
			(net "SMB_SMLINK0_STBY_LVC3_SCL_R")
		)
		(pad "2" smd rect
			(at 0 0.889 270)
			(size 0.508 0.508)
			(layers "B.Cu" "B.Mask" "B.Paste")
			(net "SMB_SMLINK0_STBY_LVC3_SCL")
		)
		(zone
			(layer "B.Cu")
			(hatch none 0.5)
			(connect_pads
				(clearance 0)
			)
			(min_thickness 0.25)
			(keepout
				(tracks allowed)
				(vias not_allowed)
				(pads allowed)
				(copperpour not_allowed)
				(footprints allowed)
			)
			(placement
				(enabled no)
				(sheetname "")
			)
			(fill
				(thermal_gap 0.5)
				(thermal_bridge_width 0.5)
				(island_removal_mode 0)
			)
			(polygon
				(pts
					(xy 427.6725 -20.574) (xy 427.6725 -20.066) (xy 428.0535 -20.066) (xy 428.0535 -20.574)
				)
			)
		)
		(zone
			(layer "B.Cu")
			(hatch none 0.5)
			(connect_pads
				(clearance 0)
			)
			(min_thickness 0.25)
			(keepout
				(tracks not_allowed)
				(vias allowed)
				(pads allowed)
				(copperpour not_allowed)
				(footprints allowed)
			)
			(placement
				(enabled no)
				(sheetname "")
			)
			(fill
				(thermal_gap 0.5)
				(thermal_bridge_width 0.5)
				(island_removal_mode 0)
			)
			(polygon
				(pts
					(xy 428.0535 -20.574) (xy 428.0535 -20.066) (xy 427.6725 -20.066) (xy 427.6725 -20.574)
				)
			)
		)
	)
	(footprint ""
		(layer "B.Cu")
		(at 422.47312 -73.962514)
		(property "Reference" "C1R27"
			(at 0 0 0)
			(layer "B.SilkS")
			(hide yes)
			(effects
				(font
					(size 1.27 1.27)
				)
				(justify mirror)
			)
		)
		(property "Value" ""
			(at 0 0 0)
			(layer "B.Fab")
			(effects
				(font
					(size 1.27 1.27)
				)
				(justify mirror)
			)
		)
		(duplicate_pad_numbers_are_jumpers no)
		(fp_poly
			(pts
				(xy -0.3048 -0.1016) (xy -0.3048 0.9906) (xy 0.3048 0.9906) (xy 0.3048 -0.1016)
			)
			(stroke
				(width 0)
				(type default)
			)
			(fill no)
			(layer "B.CrtYd")
		)
		(fp_line
			(start -0.3048 -0.1016)
			(end 0.3048 -0.1016)
			(stroke
				(width 0.1)
				(type default)
			)
			(layer "B.Fab")
		)
		(fp_line
			(start -0.3048 0.9906)
			(end -0.3048 -0.1016)
			(stroke
				(width 0.1)
				(type default)
			)
			(layer "B.Fab")
		)
		(fp_line
			(start 0.3048 -0.1016)
			(end 0.3048 0.9906)
			(stroke
				(width 0.1)
				(type default)
			)
			(layer "B.Fab")
		)
		(fp_line
			(start 0.3048 0.9906)
			(end -0.3048 0.9906)
			(stroke
				(width 0.1)
				(type default)
			)
			(layer "B.Fab")
		)
		(pad "1" smd rect
			(at 0 0 180)
			(size 0.508 0.508)
			(layers "B.Cu" "B.Mask" "B.Paste")
			(net "P3V3_STBY")
		)
		(pad "2" smd rect
			(at 0 0.889 180)
			(size 0.508 0.508)
			(layers "B.Cu" "B.Mask" "B.Paste")
			(net "GND")
		)
		(zone
			(layer "B.Cu")
			(hatch none 0.5)
			(connect_pads
				(clearance 0)
			)
			(min_thickness 0.25)
			(keepout
				(tracks allowed)
				(vias not_allowed)
				(pads allowed)
				(copperpour not_allowed)
				(footprints allowed)
			)
			(placement
				(enabled no)
				(sheetname "")
			)
			(fill
				(thermal_gap 0.5)
				(thermal_bridge_width 0.5)
				(island_removal_mode 0)
			)
			(polygon
				(pts
					(xy 422.72712 -73.708514) (xy 422.21912 -73.708514) (xy 422.21912 -73.327514) (xy 422.72712 -73.327514)
				)
			)
		)
		(zone
			(layer "B.Cu")
			(hatch none 0.5)
			(connect_pads
				(clearance 0)
			)
			(min_thickness 0.25)
			(keepout
				(tracks not_allowed)
				(vias allowed)
				(pads allowed)
				(copperpour not_allowed)
				(footprints allowed)
			)
			(placement
				(enabled no)
				(sheetname "")
			)
			(fill
				(thermal_gap 0.5)
				(thermal_bridge_width 0.5)
				(island_removal_mode 0)
			)
			(polygon
				(pts
					(xy 422.72712 -73.327514) (xy 422.21912 -73.327514) (xy 422.21912 -73.708514) (xy 422.72712 -73.708514)
				)
			)
		)
	)
)
